# T6G (Grand Teton) — schematic netlist excerpt (pin names and nets, part order shuffled) for the footprints in the layout excerpt that follows; sources: Cadence DE-HDL packaged netlist, KiCad conversion of 04192023_DAF0TMB3IC0_F0TG_MB_C_brd_V02_OCP.brd

PC508_11P1_2  Q_CAP  2.2UF 10V 10% X6S  pkg C0402  page 225 : A = PVDD11_S3_P1_PVCC ; B = GND
R1521  Q_RES  0 5% CHIP  pkg 0402LF  page 141 : A = P12V_OCP_V3_2_BUF_EN_R ; B = P3V3_OCP_EN_2
L4  Q_INDUCTOR  100NH/16A IND  pkg SMLF  page 323 : \1\ = P0V9_CPU1_RT_2D ; \2\ = P0V9_CPU1_RT0_2A

(kicad_pcb
	(version 20260206)
	(generator "pcbnew")
	(generator_version "10.0")
	(general
		(thickness 1.6)
		(legacy_teardrops no)
	)
	(paper "A4")
	(title_block
		(title "04192023_DAF0TMB3IC0_F0TG_MB_C_brd_V02_OCP.brd")
		(comment 1 "Grand Teton / footprints 1607-1609 of 8354")
	)
	(layers
		(0 "F.Cu" signal "TOP")
		(4 "In1.Cu" signal "GND")
		(6 "In2.Cu" signal "IN1")
		(8 "In3.Cu" signal "GND1")
		(10 "In4.Cu" signal "IN2")
		(12 "In5.Cu" signal "GND2")
		(14 "In6.Cu" signal "IN3")
		(16 "In7.Cu" signal "GND3")
		(18 "In8.Cu" signal "VCC")
		(20 "In9.Cu" signal "VCC1")
		(22 "In10.Cu" signal "GND4")
		(24 "In11.Cu" signal "IN4")
		(26 "In12.Cu" signal "GND5")
		(28 "In13.Cu" signal "IN5")
		(30 "In14.Cu" signal "GND6")
		(32 "In15.Cu" signal "IN6")
		(34 "In16.Cu" signal "GND7")
		(2 "B.Cu" signal "BOTTOM")
		(9 "F.Adhes" user "F.Adhesive")
		(11 "B.Adhes" user "B.Adhesive")
		(13 "F.Paste" user "Package Geometry/Pastemask Top")
		(15 "B.Paste" user "Package Geometry/Pastemask Bottom")
		(5 "F.SilkS" user "Ref Des/Silkscreen Top")
		(7 "B.SilkS" user "Ref Des/Silkscreen Bottom")
		(1 "F.Mask" user "Board Geometry/Soldermask Top")
		(3 "B.Mask" user "Board Geometry/Soldermask Bottom")
		(17 "Dwgs.User" user "User.Drawings")
		(19 "Cmts.User" user "User.Comments")
		(21 "Eco1.User" user "User.Eco1")
		(23 "Eco2.User" user "User.Eco2")
		(25 "Edge.Cuts" user "Board Geometry/Outline")
		(27 "Margin" user)
		(31 "F.CrtYd" user "Package Geometry/Place Bound Top")
		(29 "B.CrtYd" user "Package Geometry/Place Bound Bottom")
		(35 "F.Fab" user "Ref Des/Assembly Top")
		(33 "B.Fab" user "Ref Des/Assembly Bottom")
	)
	(footprint ""
		(layer "F.Cu")
		(at 56.858408 -36.75634 180)
		(property "Reference" "R1521"
			(at 0 0 180)
			(layer "F.SilkS")
			(hide yes)
			(effects
				(font
					(size 1.27 1.27)
				)
			)
		)
		(property "Value" ""
			(at 0 0 180)
			(layer "F.Fab")
			(effects
				(font
					(size 1.27 1.27)
				)
			)
		)
		(duplicate_pad_numbers_are_jumpers no)
		(fp_line
			(start 0.7874 0.4064)
			(end -0.7874 0.4064)
			(stroke
				(width 0.1524)
				(type default)
			)
			(layer "F.SilkS")
		)
		(fp_line
			(start 0.7874 -0.4064)
			(end 0.7874 0.4064)
			(stroke
				(width 0.1524)
				(type default)
			)
			(layer "F.SilkS")
		)
		(fp_line
			(start -0.7874 0.4064)
			(end -0.7874 -0.4064)
			(stroke
				(width 0.1524)
				(type default)
			)
			(layer "F.SilkS")
		)
		(fp_line
			(start -0.7874 -0.4064)
			(end 0.7874 -0.4064)
			(stroke
				(width 0.1524)
				(type default)
			)
			(layer "F.SilkS")
		)
		(fp_line
			(start 0.67945 0.3048)
			(end 0.120396 0.3048)
			(stroke
				(width 0.1)
				(type default)
			)
			(layer "F.Fab")
		)
		(fp_line
			(start 0.67945 -0.3048)
			(end 0.67945 0.3048)
			(stroke
				(width 0.1)
				(type default)
			)
			(layer "F.Fab")
		)
		(fp_line
			(start 0.12065 -0.2794)
			(end 0.12065 -0.3048)
			(stroke
				(width 0.1)
				(type default)
			)
			(layer "F.Fab")
		)
		(fp_line
			(start 0.12065 -0.3048)
			(end 0.67945 -0.3048)
			(stroke
				(width 0.1)
				(type default)
			)
			(layer "F.Fab")
		)
		(fp_line
			(start 0.120396 0.3048)
			(end 0.120396 0.2794)
			(stroke
				(width 0.1)
				(type default)
			)
			(layer "F.Fab")
		)
		(fp_line
			(start 0.120396 0.2794)
			(end -0.12065 0.2794)
			(stroke
				(width 0.1)
				(type default)
			)
			(layer "F.Fab")
		)
		(fp_line
			(start -0.12065 0.3048)
			(end -0.67945 0.3048)
			(stroke
				(width 0.1)
				(type default)
			)
			(layer "F.Fab")
		)
		(fp_line
			(start -0.12065 0.2794)
			(end -0.12065 0.3048)
			(stroke
				(width 0.1)
				(type default)
			)
			(layer "F.Fab")
		)
		(fp_line
			(start -0.12065 -0.2794)
			(end 0.12065 -0.2794)
			(stroke
				(width 0.1)
				(type default)
			)
			(layer "F.Fab")
		)
		(fp_line
			(start -0.12065 -0.305054)
			(end -0.12065 -0.2794)
			(stroke
				(width 0.1)
				(type default)
			)
			(layer "F.Fab")
		)
		(fp_line
			(start -0.67945 0.3048)
			(end -0.67945 -0.305054)
			(stroke
				(width 0.1)
				(type default)
			)
			(layer "F.Fab")
		)
		(fp_line
			(start -0.67945 -0.305054)
			(end -0.12065 -0.305054)
			(stroke
				(width 0.1)
				(type default)
			)
			(layer "F.Fab")
		)
		(pad "1" smd circle
			(at -0.40005 0 180)
			(size 0 0)
			(layers "F.Cu" "F.Mask" "F.Paste")
			(net "P12V_OCP_V3_2_BUF_EN_R")
		)
		(pad "2" smd circle
			(at 0.40005 0 180)
			(size 0 0)
			(layers "F.Cu" "F.Mask" "F.Paste")
			(net "P3V3_OCP_EN_2")
		)
	)
	(footprint ""
		(layer "F.Cu")
		(at 42.3164 -396.0368 -90)
		(property "Reference" "L4"
			(at -3.60553 2.3114 0)
			(unlocked yes)
			(layer "F.SilkS")
			(effects
				(font
					(size 0.7874 0.5842)
					(thickness 0.1524)
				)
				(justify left)
			)
		)
		(property "Value" ""
			(at 0 0 270)
			(layer "F.Fab")
			(effects
				(font
					(size 1.27 1.27)
				)
			)
		)
		(duplicate_pad_numbers_are_jumpers no)
		(fp_line
			(start -2.249932 2.249932)
			(end -2.249932 1.3843)
			(stroke
				(width 0.1524)
				(type default)
			)
			(layer "F.SilkS")
		)
		(fp_line
			(start 2.249932 2.249932)
			(end -2.249932 2.249932)
			(stroke
				(width 0.1524)
				(type default)
			)
			(layer "F.SilkS")
		)
		(fp_line
			(start 2.249932 1.3843)
			(end 2.249932 2.249932)
			(stroke
				(width 0.1524)
				(type default)
			)
			(layer "F.SilkS")
		)
		(fp_line
			(start -2.249932 -1.3843)
			(end -2.249932 -2.249932)
			(stroke
				(width 0.1524)
				(type default)
			)
			(layer "F.SilkS")
		)
		(fp_line
			(start -2.249932 -2.249932)
			(end 2.249932 -2.249932)
			(stroke
				(width 0.1524)
				(type default)
			)
			(layer "F.SilkS")
		)
		(fp_line
			(start 2.249932 -2.249932)
			(end 2.249932 -1.3843)
			(stroke
				(width 0.1524)
				(type default)
			)
			(layer "F.SilkS")
		)
		(fp_line
			(start -2.249932 2.249932)
			(end -2.249932 -2.249932)
			(stroke
				(width 0.1)
				(type default)
			)
			(layer "F.Fab")
		)
		(fp_line
			(start 2.249932 2.249932)
			(end -2.249932 2.249932)
			(stroke
				(width 0.1)
				(type default)
			)
			(layer "F.Fab")
		)
		(fp_line
			(start -2.249932 -2.249932)
			(end 2.249932 -2.249932)
			(stroke
				(width 0.1)
				(type default)
			)
			(layer "F.Fab")
		)
		(fp_line
			(start 2.249932 -2.249932)
			(end 2.249932 2.249932)
			(stroke
				(width 0.1)
				(type default)
			)
			(layer "F.Fab")
		)
		(pad "1" smd rect
			(at -1.82499 0 270)
			(size 1.0668 2.5146)
			(layers "F.Cu" "F.Mask" "F.Paste")
			(net "P0V9_CPU1_RT_2D")
		)
		(pad "2" smd rect
			(at 1.82499 0 270)
			(size 1.0668 2.5146)
			(layers "F.Cu" "F.Mask" "F.Paste")
			(net "P0V9_CPU1_RT0_2A")
		)
	)
	(footprint ""
		(layer "F.Cu")
		(at 187.563506 -351.319084 -90)
		(property "Reference" "PC508_11P1_2"
			(at 0 0 270)
			(layer "F.SilkS")
			(hide yes)
			(effects
				(font
					(size 1.27 1.27)
				)
			)
		)
		(property "Value" ""
			(at 0 0 270)
			(layer "F.Fab")
			(effects
				(font
					(size 1.27 1.27)
				)
			)
		)
		(duplicate_pad_numbers_are_jumpers no)
		(fp_line
			(start -0.7874 0.4064)
			(end -0.7874 -0.4064)
			(stroke
				(width 0.1524)
				(type default)
			)
			(layer "F.SilkS")
		)
		(fp_line
			(start 0.7874 0.4064)
			(end -0.7874 0.4064)
			(stroke
				(width 0.1524)
				(type default)
			)
			(layer "F.SilkS")
		)
		(fp_line
			(start -0.7874 -0.4064)
			(end 0.7874 -0.4064)
			(stroke
				(width 0.1524)
				(type default)
			)
			(layer "F.SilkS")
		)
		(fp_line
			(start 0.7874 -0.4064)
			(end 0.7874 0.4064)
			(stroke
				(width 0.1524)
				(type default)
			)
			(layer "F.SilkS")
		)
		(fp_line
			(start -0.67945 0.3048)
			(end -0.67945 -0.305054)
			(stroke
				(width 0.1)
				(type default)
			)
			(layer "F.Fab")
		)
		(fp_line
			(start -0.12065 0.3048)
			(end -0.67945 0.3048)
			(stroke
				(width 0.1)
				(type default)
			)
			(layer "F.Fab")
		)
		(fp_line
			(start 0.120396 0.3048)
			(end 0.120396 0.2794)
			(stroke
				(width 0.1)
				(type default)
			)
			(layer "F.Fab")
		)
		(fp_line
			(start 0.67945 0.3048)
			(end 0.120396 0.3048)
			(stroke
				(width 0.1)
				(type default)
			)
			(layer "F.Fab")
		)
		(fp_line
			(start -0.12065 0.2794)
			(end -0.12065 0.3048)
			(stroke
				(width 0.1)
				(type default)
			)
			(layer "F.Fab")
		)
		(fp_line
			(start 0.120396 0.2794)
			(end -0.12065 0.2794)
			(stroke
				(width 0.1)
				(type default)
			)
			(layer "F.Fab")
		)
		(fp_line
			(start -0.12065 -0.2794)
			(end 0.12065 -0.2794)
			(stroke
				(width 0.1)
				(type default)
			)
			(layer "F.Fab")
		)
		(fp_line
			(start 0.12065 -0.2794)
			(end 0.12065 -0.3048)
			(stroke
				(width 0.1)
				(type default)
			)
			(layer "F.Fab")
		)
		(fp_line
			(start 0.12065 -0.3048)
			(end 0.67945 -0.3048)
			(stroke
				(width 0.1)
				(type default)
			)
			(layer "F.Fab")
		)
		(fp_line
			(start 0.67945 -0.3048)
			(end 0.67945 0.3048)
			(stroke
				(width 0.1)
				(type default)
			)
			(layer "F.Fab")
		)
		(fp_line
			(start -0.67945 -0.305054)
			(end -0.12065 -0.305054)
			(stroke
				(width 0.1)
				(type default)
			)
			(layer "F.Fab")
		)
		(fp_line
			(start -0.12065 -0.305054)
			(end -0.12065 -0.2794)
			(stroke
				(width 0.1)
				(type default)
			)
			(layer "F.Fab")
		)
		(pad "1" smd circle
			(at -0.40005 0 270)
			(size 0 0)
			(layers "F.Cu" "F.Mask" "F.Paste")
			(net "PVDD11_S3_P1_PVCC")
		)
		(pad "2" smd circle
			(at 0.40005 0 270)
			(size 0 0)
			(layers "F.Cu" "F.Mask" "F.Paste")
			(net "GND")
		)
	)
)
